(kicad_pcb
	(version 20241229)
	(generator "pcbnew")
	(generator_version "9.0")
	(general
		(thickness 1.6296)
		(legacy_teardrops no)
	)
	(paper "A3")
	(title_block
		(title "Thunderbolt to 10GbE adapter")
		(date "2026-04-21")
		(rev "1.1.0")
		(company "Antmicro Ltd")
		(comment 1 "www.antmicro.com")
		(comment 9 "footprints 531-535 of 703")
	)
	(layers
		(0 "F.Cu" signal)
		(4 "In1.Cu" signal)
		(6 "In2.Cu" signal)
		(8 "In3.Cu" signal)
		(10 "In4.Cu" signal)
		(12 "In5.Cu" signal)
		(14 "In6.Cu" signal)
		(2 "B.Cu" signal)
		(9 "F.Adhes" user "F.Adhesive")
		(11 "B.Adhes" user "B.Adhesive")
		(13 "F.Paste" user)
		(15 "B.Paste" user)
		(5 "F.SilkS" user "F.Silkscreen")
		(7 "B.SilkS" user "B.Silkscreen")
		(1 "F.Mask" user)
		(3 "B.Mask" user)
		(17 "Dwgs.User" user "User.Drawings")
		(19 "Cmts.User" user "User.Comments")
		(21 "Eco1.User" user "User.Eco1")
		(23 "Eco2.User" user "User.Eco2")
		(25 "Edge.Cuts" user)
		(27 "Margin" user)
		(31 "F.CrtYd" user "F.Courtyard")
		(29 "B.CrtYd" user "B.Courtyard")
		(35 "F.Fab" user)
		(33 "B.Fab" user)
	)
	(footprint "antmicro-footprints:SOT-416"
		(layer "B.Cu")
		(at 178.5 75.55 -90)
		(descr "SOT-416")
		(tags "SOT-416")
		(property "Reference" "Q5"
			(at -0.75 1.3 90)
			(layer "B.SilkS")
			(effects
				(font
					(size 0.7 0.7)
					(thickness 0.15)
				)
				(justify left bottom mirror)
			)
		)
		(property "Value" "DTC014T_SOT-416"
			(at 0 -2 90)
			(layer "B.Fab")
			(effects
				(font
					(size 0.7 0.7)
					(thickness 0.15)
				)
				(justify left bottom mirror)
			)
		)
		(property "Datasheet" "https://www.rohm.com/datasheet?p=DTC014TEB&dist=Mouser&media=referral&source=mouser.com&campaign=Mouser"
			(at 0 0 90)
			(layer "B.Fab")
			(hide yes)
			(effects
				(font
					(size 1.27 1.27)
					(thickness 0.15)
				)
				(justify mirror)
			)
		)
		(property "Description" "Bipolar (BJT) Single Transistor with built-in base resistor, NPN, 50V, 100mA, 150mW, SOT-416FL, Surface Mount"
			(at 0 0 90)
			(layer "B.Fab")
			(hide yes)
			(effects
				(font
					(size 1.27 1.27)
					(thickness 0.15)
				)
				(justify mirror)
			)
		)
		(property "Manufacturer" "ROHM Semiconductor"
			(at 0 0 270)
			(unlocked yes)
			(layer "B.Fab")
			(hide yes)
			(effects
				(font
					(size 1 1)
					(thickness 0.15)
				)
				(justify mirror)
			)
		)
		(property "MPN" "DTC014TEBTL"
			(at 0 0 270)
			(unlocked yes)
			(layer "B.Fab")
			(hide yes)
			(effects
				(font
					(size 1 1)
					(thickness 0.15)
				)
				(justify mirror)
			)
		)
		(property "Author" "Antmicro"
			(at 0 0 270)
			(unlocked yes)
			(layer "B.Fab")
			(hide yes)
			(effects
				(font
					(size 1 1)
					(thickness 0.15)
				)
				(justify mirror)
			)
		)
		(property "License" "Apache-2.0"
			(at 0 0 270)
			(unlocked yes)
			(layer "B.Fab")
			(hide yes)
			(effects
				(font
					(size 1 1)
					(thickness 0.15)
				)
				(justify mirror)
			)
		)
		(sheetname "/X710 DCDC converters/")
		(sheetfile "DCDC_converters_X710.kicad_sch")
		(attr smd)
		(fp_line
			(start 0.508 0.9)
			(end -0.5 0.9)
			(stroke
				(width 0.15)
				(type solid)
			)
			(layer "B.SilkS")
		)
		(fp_line
			(start 0.508 0.9)
			(end 0.508 0.592)
			(stroke
				(width 0.15)
				(type solid)
			)
			(layer "B.SilkS")
		)
		(fp_line
			(start -0.5 0.15)
			(end -0.5 -0.15)
			(stroke
				(width 0.15)
				(type solid)
			)
			(layer "B.SilkS")
		)
		(fp_line
			(start 0.5 -0.9)
			(end 0.5 -0.7)
			(stroke
				(width 0.15)
				(type solid)
			)
			(layer "B.SilkS")
		)
		(fp_line
			(start 0.5 -0.9)
			(end -0.5 -0.9)
			(stroke
				(width 0.15)
				(type solid)
			)
			(layer "B.SilkS")
		)
		(fp_rect
			(start -1 1.05)
			(end 1 -1.05)
			(stroke
				(width 0.05)
				(type solid)
			)
			(fill no)
			(layer "B.CrtYd")
		)
		(fp_line
			(start -0.05 0.9)
			(end -0.45 0.5)
			(stroke
				(width 0.15)
				(type solid)
			)
			(layer "B.Fab")
		)
		(fp_rect
			(start 0.45 -0.9)
			(end -0.45 0.9)
			(stroke
				(width 0.15)
				(type solid)
			)
			(fill no)
			(layer "B.Fab")
		)
		(fp_text user "Author: Antmicro"
			(at -1 -4.602 90)
			(layer "B.Fab")
			(effects
				(font
					(size 0.7 0.7)
					(thickness 0.15)
				)
				(justify left bottom mirror)
			)
		)
		(fp_text user "License: Apache-2.0"
			(at -1 -5.802 90)
			(layer "B.Fab")
			(effects
				(font
					(size 0.7 0.7)
					(thickness 0.15)
				)
				(justify left bottom mirror)
			)
		)
		(fp_text user "${REFERENCE}"
			(at -1 -3.4 90)
			(layer "B.Fab")
			(effects
				(font
					(size 0.7 0.7)
					(thickness 0.15)
				)
				(justify left bottom mirror)
			)
		)
		(pad "1" smd rect
			(at -0.652 0.5 270)
			(size 0.6 0.5)
			(layers "B.Cu" "B.Mask" "B.Paste")
			(net 341 "/X710 DCDC converters/+DVDD_OUT")
			(pinfunction "B")
			(pintype "input")
		)
		(pad "2" smd rect
			(at -0.652 -0.498 270)
			(size 0.6 0.5)
			(layers "B.Cu" "B.Mask" "B.Paste")
			(net 23 "GND")
			(pinfunction "E")
			(pintype "passive")
		)
		(pad "3" smd rect
			(at 0.65 0 270)
			(size 0.6 0.5)
			(layers "B.Cu" "B.Mask" "B.Paste")
			(net 431 "Net-(Q5-C)")
			(pinfunction "C")
			(pintype "passive")
		)
	)
	(footprint "antmicro-footprints:TP_SMD_0.75mm"
		(layer "B.Cu")
		(at 183.75 81.75 90)
		(property "Reference" "TP17"
			(at -10.75 0.75 270)
			(layer "B.SilkS")
			(effects
				(font
					(size 0.7 0.7)
					(thickness 0.15)
				)
				(justify left bottom mirror)
			)
		)
		(property "Value" "TP_0.75mm_SMD"
			(at 0 -1.2 270)
			(layer "B.Fab")
			(effects
				(font
					(size 0.7 0.7)
					(thickness 0.15)
				)
				(justify left bottom mirror)
			)
		)
		(property "Description" "SMT test point"
			(at 0 0 270)
			(layer "B.Fab")
			(hide yes)
			(effects
				(font
					(size 1.27 1.27)
					(thickness 0.15)
				)
				(justify mirror)
			)
		)
		(property "MPN" ""
			(at 0 0 90)
			(unlocked yes)
			(layer "B.Fab")
			(hide yes)
			(effects
				(font
					(size 1 1)
					(thickness 0.15)
				)
				(justify mirror)
			)
		)
		(property "Manufacturer" ""
			(at 0 0 90)
			(unlocked yes)
			(layer "B.Fab")
			(hide yes)
			(effects
				(font
					(size 1 1)
					(thickness 0.15)
				)
				(justify mirror)
			)
		)
		(property "Author" "Antmicro"
			(at 0 0 90)
			(unlocked yes)
			(layer "B.Fab")
			(hide yes)
			(effects
				(font
					(size 1 1)
					(thickness 0.15)
				)
				(justify mirror)
			)
		)
		(property "License" "Apache-2.0"
			(at 0 0 90)
			(unlocked yes)
			(layer "B.Fab")
			(hide yes)
			(effects
				(font
					(size 1 1)
					(thickness 0.15)
				)
				(justify mirror)
			)
		)
		(sheetname "/X710 DCDC converters/")
		(sheetfile "DCDC_converters_X710.kicad_sch")
		(attr exclude_from_pos_files exclude_from_bom)
		(fp_circle
			(center 0 0)
			(end 0.475 0)
			(stroke
				(width 0.05)
				(type default)
			)
			(fill no)
			(layer "B.CrtYd")
		)
		(fp_text user "${REFERENCE}"
			(at -0.4 -2.7 270)
			(layer "B.Fab")
			(effects
				(font
					(size 0.7 0.7)
					(thickness 0.15)
				)
				(justify left bottom mirror)
			)
		)
		(fp_text user "License: Apache-2.0"
			(at -0.4 -5.101 270)
			(layer "B.Fab")
			(effects
				(font
					(size 0.7 0.7)
					(thickness 0.15)
				)
				(justify left bottom mirror)
			)
		)
		(fp_text user "Author: Antmicro"
			(at -0.4 -3.901 270)
			(layer "B.Fab")
			(effects
				(font
					(size 0.7 0.7)
					(thickness 0.15)
				)
				(justify left bottom mirror)
			)
		)
		(pad "1" smd circle
			(at 0 0 90)
			(size 0.75 0.75)
			(layers "B.Cu" "B.Mask")
			(net 18 "+1V88")
			(pinfunction "1")
			(pintype "passive")
		)
	)
	(footprint "antmicro-footprints:C_0402_1005Metric"
		(layer "B.Cu")
		(at 128.009999 116.655001 180)
		(descr "Capacitor SMD 0402")
		(tags "capacitor SMD 0402")
		(property "Reference" "C97"
			(at -21.900002 7.700002 0)
			(layer "B.SilkS")
			(effects
				(font
					(size 0.7 0.7)
					(thickness 0.15)
				)
				(justify mirror)
			)
		)
		(property "Value" "C_10u_0402"
			(at -1.022927 -2.155213 0)
			(layer "B.Fab")
			(effects
				(font
					(size 0.7 0.7)
					(thickness 0.15)
				)
				(justify left bottom mirror)
			)
		)
		(property "Datasheet" "https://www.yageo.com/en/Chart/Download/pdf/CC0402MRX5R5BB106"
			(at 0 0 0)
			(layer "B.Fab")
			(hide yes)
			(effects
				(font
					(size 1.27 1.27)
					(thickness 0.15)
				)
				(justify mirror)
			)
		)
		(property "Description" "SMD Multilayer Ceramic Capacitor, 10 µF, 6.3 V, 0402 [1005 Metric], ± 20%, X5R, CC Series"
			(at 0 0 0)
			(layer "B.Fab")
			(hide yes)
			(effects
				(font
					(size 1.27 1.27)
					(thickness 0.15)
				)
				(justify mirror)
			)
		)
		(property "MPN" "CC0402MRX5R5BB106"
			(at 0 0 180)
			(unlocked yes)
			(layer "B.Fab")
			(hide yes)
			(effects
				(font
					(size 1 1)
					(thickness 0.15)
				)
				(justify mirror)
			)
		)
		(property "Manufacturer" "YAGEO"
			(at 0 0 180)
			(unlocked yes)
			(layer "B.Fab")
			(hide yes)
			(effects
				(font
					(size 1 1)
					(thickness 0.15)
				)
				(justify mirror)
			)
		)
		(property "License" "Apache-2.0"
			(at 0 0 180)
			(unlocked yes)
			(layer "B.Fab")
			(hide yes)
			(effects
				(font
					(size 1 1)
					(thickness 0.15)
				)
				(justify mirror)
			)
		)
		(property "Val" "10u"
			(at 0 0 180)
			(unlocked yes)
			(layer "B.Fab")
			(hide yes)
			(effects
				(font
					(size 1 1)
					(thickness 0.15)
				)
				(justify mirror)
			)
		)
		(property "Voltage" ""
			(at 0 0 180)
			(unlocked yes)
			(layer "B.Fab")
			(hide yes)
			(effects
				(font
					(size 1 1)
					(thickness 0.15)
				)
				(justify mirror)
			)
		)
		(property "Dielectric" ""
			(at 0 0 180)
			(unlocked yes)
			(layer "B.Fab")
			(hide yes)
			(effects
				(font
					(size 1 1)
					(thickness 0.15)
				)
				(justify mirror)
			)
		)
		(property "Author" "Antmicro"
			(at 0 0 180)
			(unlocked yes)
			(layer "B.Fab")
			(hide yes)
			(effects
				(font
					(size 1 1)
					(thickness 0.15)
				)
				(justify mirror)
			)
		)
		(sheetname "/TB Controller - Power/")
		(sheetfile "tb-power.kicad_sch")
		(attr smd)
		(fp_rect
			(start -0.925 0.47)
			(end 0.925 -0.47)
			(stroke
				(width 0.05)
				(type default)
			)
			(fill no)
			(layer "B.CrtYd")
		)
		(fp_line
			(start 0.504 0.25)
			(end 0.504 -0.248)
			(stroke
				(width 0.15)
				(type solid)
			)
			(layer "B.Fab")
		)
		(fp_line
			(start 0.504 -0.248)
			(end -0.494 -0.248)
			(stroke
				(width 0.15)
				(type solid)
			)
			(layer "B.Fab")
		)
		(fp_line
			(start -0.494 0.25)
			(end 0.504 0.25)
			(stroke
				(width 0.15)
				(type solid)
			)
			(layer "B.Fab")
		)
		(fp_line
			(start -0.494 -0.248)
			(end -0.494 0.25)
			(stroke
				(width 0.15)
				(type solid)
			)
			(layer "B.Fab")
		)
		(fp_text user "Author: Antmicro"
			(at -0.939 -3.399 0)
			(layer "B.Fab")
			(effects
				(font
					(size 0.7 0.7)
					(thickness 0.15)
				)
				(justify left bottom mirror)
			)
		)
		(fp_text user "${REFERENCE}"
			(at -0.939 -4.599 0)
			(layer "B.Fab")
			(effects
				(font
					(size 0.7 0.7)
					(thickness 0.15)
				)
				(justify left bottom mirror)
			)
		)
		(fp_text user "License: Apache-2.0"
			(at -0.939 -5.799 0)
			(layer "B.Fab")
			(effects
				(font
					(size 0.7 0.7)
					(thickness 0.15)
				)
				(justify left bottom mirror)
			)
		)
		(pad "1" smd roundrect
			(at -0.48 0 180)
			(size 0.59 0.64)
			(layers "B.Cu" "B.Mask" "B.Paste")
			(roundrect_rratio 0.25)
			(net 23 "GND")
			(pintype "passive")
		)
		(pad "2" smd roundrect
			(at 0.48 0 180)
			(size 0.59 0.64)
			(layers "B.Cu" "B.Mask" "B.Paste")
			(roundrect_rratio 0.25)
			(net 181 "Net-(U4A-VCC3P3_S0)")
			(pintype "passive")
		)
	)
	(footprint "antmicro-footprints:TP_SMD_0.75mm"
		(layer "B.Cu")
		(at 156.731866 62.935117 180)
		(property "Reference" "TP28"
			(at -0.268134 3.135117 270)
			(layer "B.SilkS")
			(effects
				(font
					(size 0.7 0.7)
					(thickness 0.15)
				)
				(justify left bottom mirror)
			)
		)
		(property "Value" "TP_0.75mm_SMD"
			(at 0 -1.2 0)
			(layer "B.Fab")
			(effects
				(font
					(size 0.7 0.7)
					(thickness 0.15)
				)
				(justify left bottom mirror)
			)
		)
		(property "Description" "SMT test point"
			(at 0 0 0)
			(layer "B.Fab")
			(hide yes)
			(effects
				(font
					(size 1.27 1.27)
					(thickness 0.15)
				)
				(justify mirror)
			)
		)
		(property "MPN" ""
			(at 0 0 180)
			(unlocked yes)
			(layer "B.Fab")
			(hide yes)
			(effects
				(font
					(size 1 1)
					(thickness 0.15)
				)
				(justify mirror)
			)
		)
		(property "Manufacturer" ""
			(at 0 0 180)
			(unlocked yes)
			(layer "B.Fab")
			(hide yes)
			(effects
				(font
					(size 1 1)
					(thickness 0.15)
				)
				(justify mirror)
			)
		)
		(property "Author" "Antmicro"
			(at 0 0 180)
			(unlocked yes)
			(layer "B.Fab")
			(hide yes)
			(effects
				(font
					(size 1 1)
					(thickness 0.15)
				)
				(justify mirror)
			)
		)
		(property "License" "Apache-2.0"
			(at 0 0 180)
			(unlocked yes)
			(layer "B.Fab")
			(hide yes)
			(effects
				(font
					(size 1 1)
					(thickness 0.15)
				)
				(justify mirror)
			)
		)
		(sheetname "/X710-AT2 Misc/")
		(sheetfile "x710-at2-mics.kicad_sch")
		(attr exclude_from_pos_files exclude_from_bom)
		(fp_circle
			(center 0 0)
			(end 0.475 0)
			(stroke
				(width 0.05)
				(type default)
			)
			(fill no)
			(layer "B.CrtYd")
		)
		(fp_text user "${REFERENCE}"
			(at -0.4 -2.7 0)
			(layer "B.Fab")
			(effects
				(font
					(size 0.7 0.7)
					(thickness 0.15)
				)
				(justify left bottom mirror)
			)
		)
		(fp_text user "Author: Antmicro"
			(at -0.4 -3.901 0)
			(layer "B.Fab")
			(effects
				(font
					(size 0.7 0.7)
					(thickness 0.15)
				)
				(justify left bottom mirror)
			)
		)
		(fp_text user "License: Apache-2.0"
			(at -0.4 -5.101 0)
			(layer "B.Fab")
			(effects
				(font
					(size 0.7 0.7)
					(thickness 0.15)
				)
				(justify left bottom mirror)
			)
		)
		(pad "1" smd circle
			(at 0 0 180)
			(size 0.75 0.75)
			(layers "B.Cu" "B.Mask")
			(net 138 "/X710-AT2 Misc/NCSI.TXD_1")
			(pinfunction "1")
			(pintype "passive")
		)
	)
	(footprint "antmicro-footprints:C_0402_1005Metric"
		(layer "B.Cu")
		(at 154.261866 87.265117 180)
		(descr "Capacitor SMD 0402")
		(tags "capacitor SMD 0402")
		(property "Reference" "C208"
			(at -17.938134 -9.464883 0)
			(layer "B.SilkS")
			(effects
				(font
					(size 0.7 0.7)
					(thickness 0.15)
				)
				(justify mirror)
			)
		)
		(property "Value" "C_1u_25V_0402"
			(at -1.022927 -2.155213 0)
			(layer "B.Fab")
			(effects
				(font
					(size 0.7 0.7)
					(thickness 0.15)
				)
				(justify left bottom mirror)
			)
		)
		(property "Datasheet" "https://www.murata.com/products/productdetail?partno=GRM155R61E105KE11%23"
			(at 0 0 0)
			(layer "B.Fab")
			(hide yes)
			(effects
				(font
					(size 1.27 1.27)
					(thickness 0.15)
				)
				(justify mirror)
			)
		)
		(property "Description" "SMD Multilayer Ceramic Capacitor, 1 µF, 25 V, 0402 [1005 Metric], ± 10%, X5R, GRM Series"
			(at 0 0 0)
			(layer "B.Fab")
			(hide yes)
			(effects
				(font
					(size 1.27 1.27)
					(thickness 0.15)
				)
				(justify mirror)
			)
		)
		(property "MPN" "GRM155R61E105KE11J"
			(at 0 0 180)
			(unlocked yes)
			(layer "B.Fab")
			(hide yes)
			(effects
				(font
					(size 1 1)
					(thickness 0.15)
				)
				(justify mirror)
			)
		)
		(property "Manufacturer" "Murata"
			(at 0 0 180)
			(unlocked yes)
			(layer "B.Fab")
			(hide yes)
			(effects
				(font
					(size 1 1)
					(thickness 0.15)
				)
				(justify mirror)
			)
		)
		(property "License" "Apache-2.0"
			(at 0 0 180)
			(unlocked yes)
			(layer "B.Fab")
			(hide yes)
			(effects
				(font
					(size 1 1)
					(thickness 0.15)
				)
				(justify mirror)
			)
		)
		(property "Author" "Antmicro"
			(at 0 0 180)
			(unlocked yes)
			(layer "B.Fab")
			(hide yes)
			(effects
				(font
					(size 1 1)
					(thickness 0.15)
				)
				(justify mirror)
			)
		)
		(property "Val" "1u"
			(at 0 0 180)
			(unlocked yes)
			(layer "B.Fab")
			(hide yes)
			(effects
				(font
					(size 1 1)
					(thickness 0.15)
				)
				(justify mirror)
			)
		)
		(property "Voltage" "25V"
			(at 0 0 180)
			(unlocked yes)
			(layer "B.Fab")
			(hide yes)
			(effects
				(font
					(size 1 1)
					(thickness 0.15)
				)
				(justify mirror)
			)
		)
		(property "Dielectric" "X5R"
			(at 0 0 180)
			(unlocked yes)
			(layer "B.Fab")
			(hide yes)
			(effects
				(font
					(size 1 1)
					(thickness 0.15)
				)
				(justify mirror)
			)
		)
		(sheetname "/X710-AT2 power/")
		(sheetfile "x710-at2-power.kicad_sch")
		(attr smd)
		(fp_rect
			(start -0.925 0.47)
			(end 0.925 -0.47)
			(stroke
				(width 0.05)
				(type default)
			)
			(fill no)
			(layer "B.CrtYd")
		)
		(fp_line
			(start 0.504 0.25)
			(end 0.504 -0.248)
			(stroke
				(width 0.15)
				(type solid)
			)
			(layer "B.Fab")
		)
		(fp_line
			(start 0.504 -0.248)
			(end -0.494 -0.248)
			(stroke
				(width 0.15)
				(type solid)
			)
			(layer "B.Fab")
		)
		(fp_line
			(start -0.494 0.25)
			(end 0.504 0.25)
			(stroke
				(width 0.15)
				(type solid)
			)
			(layer "B.Fab")
		)
		(fp_line
			(start -0.494 -0.248)
			(end -0.494 0.25)
			(stroke
				(width 0.15)
				(type solid)
			)
			(layer "B.Fab")
		)
		(fp_text user "${REFERENCE}"
			(at -0.939 -4.599 0)
			(layer "B.Fab")
			(effects
				(font
					(size 0.7 0.7)
					(thickness 0.15)
				)
				(justify left bottom mirror)
			)
		)
		(fp_text user "License: Apache-2.0"
			(at -0.939 -5.799 0)
			(layer "B.Fab")
			(effects
				(font
					(size 0.7 0.7)
					(thickness 0.15)
				)
				(justify left bottom mirror)
			)
		)
		(fp_text user "Author: Antmicro"
			(at -0.939 -3.399 0)
			(layer "B.Fab")
			(effects
				(font
					(size 0.7 0.7)
					(thickness 0.15)
				)
				(justify left bottom mirror)
			)
		)
		(pad "1" smd roundrect
			(at -0.48 0 180)
			(size 0.59 0.64)
			(layers "B.Cu" "B.Mask" "B.Paste")
			(roundrect_rratio 0.25)
			(net 23 "GND")
			(pintype "passive")
		)
		(pad "2" smd roundrect
			(at 0.48 0 180)
			(size 0.59 0.64)
			(layers "B.Cu" "B.Mask" "B.Paste")
			(roundrect_rratio 0.25)
			(net 21 "XFI_PVDD")
			(pintype "passive")
		)
	)
)
